A
A
B
B
C
C
D
D
E
E
F
F
1
1
2
2
3
3
4
4
U2
View from Top side (apx. Scale 2:1)
R6
C9
C4
R2
R5
R4
R1
C12
C3
C2
C6
C1
R3
U3
C11
C10
C8
C5
C7
L1
J6
J5
J4
J3
J2
J1
P10
P9
P8
P7
P6
P5
P2
P4
P3
P1
View from Bottom side (apx. Scale 2:1)
Assemble and inspect per IPC-A-610 (current revision) CLASS 2.
1.
This assembly drawing shows all component locations for all board stuff options. Refer to the specific BOM for assembly specific 
components.
2.
Final assembly shall be compliant with RoHS directive 2011/65/EU and California Proposition 65.
3.
Board edge to be deburred and free of sharp edges.
4.
Boards must be clean and free of flux. Wash with aqueous based solution or equivalent if neceessary.
5.
Packaging:
     A. Individual PCBAs must be individually packed in ANSI/ESD S20.20 compliant bags.
     B. Individually packed FPCAs must also include a rigid backer in the bag.
     C. Trays of PCBAs shall be delivered packed in ANSI/ESD S20.20 compliant materials and marked with cautionary ESD labeling.
6.
Pins P1-P10 are Press-Fit Pins
7.
NOTES: UNLESS OTHERWISE SPECIFIED
REV
X1
DESCRIPTION
INITIAL RELEASE
DATE
01/24/2023
APPROVED
 SHEET:            OF
 CAGE CODE:
SIZE:
B
.It
REV:
 DWG NO:
=CAGE_CO
 SCALE:   
1 
1 
=DOC_NO_ASSY_
DWG NO:
REV:
.Ite
PCBA_SA45_DaughterCard.PCBDwf
 FILE NAME:
1:1 
7
